(kicad_pcb
	(version 20241229)
	(generator "pcbnew")
	(generator_version "9.0")
	(general
		(thickness 1.61)
		(legacy_teardrops no)
	)
	(paper "A3")
	(title_block
		(title "SO-DIMM DDR5 Tester")
		(date "2025-11-26")
		(rev "1.3.0")
		(comment 9 "footprints 66-70 of 627")
	)
	(layers
		(0 "F.Cu" signal)
		(4 "In1.Cu" power)
		(6 "In2.Cu" mixed)
		(8 "In3.Cu" power)
		(10 "In4.Cu" mixed)
		(12 "In5.Cu" power)
		(14 "In6.Cu" mixed)
		(16 "In7.Cu" power)
		(18 "In8.Cu" power)
		(20 "In9.Cu" mixed)
		(22 "In10.Cu" power)
		(2 "B.Cu" signal)
		(9 "F.Adhes" user "F.Adhesive")
		(11 "B.Adhes" user "B.Adhesive")
		(13 "F.Paste" user)
		(15 "B.Paste" user)
		(5 "F.SilkS" user "F.Silkscreen")
		(7 "B.SilkS" user "B.Silkscreen")
		(1 "F.Mask" user)
		(3 "B.Mask" user)
		(17 "Dwgs.User" user "User.Drawings")
		(19 "Cmts.User" user "User.Comments")
		(21 "Eco1.User" user "User.Eco1")
		(23 "Eco2.User" user "User.Eco2")
		(25 "Edge.Cuts" user)
		(27 "Margin" user)
		(31 "F.CrtYd" user "F.Courtyard")
		(29 "B.CrtYd" user "B.Courtyard")
		(35 "F.Fab" user)
		(33 "B.Fab" user)
	)
	(footprint "antmicro-footprints:C_0603_1608Metric"
		(layer "F.Cu")
		(at 199.5 189.475)
		(descr "Capacitor SMD 0603")
		(tags "capacitor 0603")
		(property "Reference" "C189"
			(at -1.42757 -1.000252 0)
			(layer "F.SilkS")
			(hide yes)
			(effects
				(font
					(size 0.7 0.7)
					(thickness 0.15)
				)
				(justify left bottom)
			)
		)
		(property "Value" "C_22u_0603"
			(at -1.42757 1.770288 0)
			(layer "F.Fab")
			(effects
				(font
					(size 0.7 0.7)
					(thickness 0.15)
				)
				(justify left bottom)
			)
		)
		(property "Datasheet" "https://www.murata.com/products/productdetail?partno=GRM188R60J226MEA0%23"
			(at 0 0 0)
			(layer "F.Fab")
			(hide yes)
			(effects
				(font
					(size 1.27 1.27)
					(thickness 0.15)
				)
			)
		)
		(property "Author" "Antmicro"
			(at 0 0 0)
			(layer "F.Fab")
			(hide yes)
			(effects
				(font
					(size 1 1)
					(thickness 0.15)
				)
			)
		)
		(property "Dielectric" ""
			(at 0 0 0)
			(layer "F.Fab")
			(hide yes)
			(effects
				(font
					(size 1 1)
					(thickness 0.15)
				)
			)
		)
		(property "License" "Apache-2.0"
			(at 0 0 0)
			(layer "F.Fab")
			(hide yes)
			(effects
				(font
					(size 1 1)
					(thickness 0.15)
				)
			)
		)
		(property "MPN" "GRM188R60J226MEA0D"
			(at 0 0 0)
			(layer "F.Fab")
			(hide yes)
			(effects
				(font
					(size 1 1)
					(thickness 0.15)
				)
			)
		)
		(property "Manufacturer" "Murata"
			(at 0 0 0)
			(layer "F.Fab")
			(hide yes)
			(effects
				(font
					(size 1 1)
					(thickness 0.15)
				)
			)
		)
		(property "Val" "22u"
			(at 0 0 0)
			(layer "F.Fab")
			(hide yes)
			(effects
				(font
					(size 1 1)
					(thickness 0.15)
				)
			)
		)
		(property "Voltage" ""
			(at 0 0 0)
			(layer "F.Fab")
			(hide yes)
			(effects
				(font
					(size 1 1)
					(thickness 0.15)
				)
			)
		)
		(sheetname "/Supply/")
		(sheetfile "supply.kicad_sch")
		(attr smd)
		(fp_line
			(start -0.3 -0.3)
			(end 0.3 -0.3)
			(stroke
				(width 0.15)
				(type solid)
			)
			(layer "F.SilkS")
		)
		(fp_line
			(start -0.3 0.3)
			(end 0.3 0.3)
			(stroke
				(width 0.15)
				(type solid)
			)
			(layer "F.SilkS")
		)
		(fp_rect
			(start -1.24 -0.7)
			(end 1.24 0.7)
			(stroke
				(width 0.05)
				(type solid)
			)
			(fill no)
			(layer "F.CrtYd")
		)
		(fp_rect
			(start -0.8 -0.4)
			(end 0.8 0.4)
			(stroke
				(width 0.15)
				(type solid)
			)
			(fill no)
			(layer "F.Fab")
		)
		(pad "1" smd roundrect
			(at -0.7 0)
			(size 0.6 0.8)
			(layers "F.Cu" "F.Mask" "F.Paste")
			(roundrect_rratio 0.2)
			(net 1 "GND")
			(pintype "passive")
		)
		(pad "2" smd roundrect
			(at 0.7 0)
			(size 0.6 0.8)
			(layers "F.Cu" "F.Mask" "F.Paste")
			(roundrect_rratio 0.2)
			(net 58 "/Supply/1V7_local")
			(pintype "passive")
		)
	)
	(footprint "antmicro-footprints:LED_0603_1608Metric_G"
		(layer "F.Cu")
		(at 97.9 197.1 -90)
		(descr "LED SMD 0603 Green")
		(tags "LED SMD 0603 Green")
		(property "Reference" "D13"
			(at -0.001 -0.901 270)
			(layer "F.SilkS")
			(hide yes)
			(effects
				(font
					(size 0.7 0.7)
					(thickness 0.15)
				)
				(justify left bottom)
			)
		)
		(property "Value" "LED_G_0603_KP-1608CGCK"
			(at -0.001 1.599 270)
			(layer "F.Fab")
			(effects
				(font
					(size 0.7 0.7)
					(thickness 0.15)
				)
				(justify left bottom)
			)
		)
		(property "Datasheet" "http://www.farnell.com/datasheets/2045956.pdf"
			(at 0 0 270)
			(layer "F.Fab")
			(hide yes)
			(effects
				(font
					(size 1.27 1.27)
					(thickness 0.15)
				)
			)
		)
		(property "Author" "Antmicro"
			(at -99.2 295 0)
			(layer "F.Fab")
			(hide yes)
			(effects
				(font
					(size 1 1)
					(thickness 0.15)
				)
			)
		)
		(property "License" "Apache-2.0"
			(at -99.2 295 0)
			(layer "F.Fab")
			(hide yes)
			(effects
				(font
					(size 1 1)
					(thickness 0.15)
				)
			)
		)
		(property "MPN" "KP-1608CGCK"
			(at -99.2 295 0)
			(layer "F.Fab")
			(hide yes)
			(effects
				(font
					(size 1 1)
					(thickness 0.15)
				)
			)
		)
		(property "Manufacturer" "Kingbright"
			(at -99.2 295 0)
			(layer "F.Fab")
			(hide yes)
			(effects
				(font
					(size 1 1)
					(thickness 0.15)
				)
			)
		)
		(sheetname "/Debug FTDI/")
		(sheetfile "debug-ftdi.kicad_sch")
		(attr smd)
		(fp_line
			(start -0.271 0.348)
			(end 0.269 0.348)
			(stroke
				(width 0.15)
				(type solid)
			)
			(layer "F.SilkS")
		)
		(fp_line
			(start 1.249 0.319)
			(end 1.249 -0.321)
			(stroke
				(width 0.15)
				(type solid)
			)
			(layer "F.SilkS")
		)
		(fp_line
			(start -0.107 -0.001)
			(end -0.291 -0.001)
			(stroke
				(width 0.1)
				(type solid)
			)
			(layer "F.SilkS")
		)
		(fp_line
			(start 0.092 -0.001)
			(end -0.107 0.198)
			(stroke
				(width 0.1)
				(type solid)
			)
			(layer "F.SilkS")
		)
		(fp_line
			(start 0.092 -0.001)
			(end 0.292 -0.001)
			(stroke
				(width 0.1)
				(type solid)
			)
			(layer "F.SilkS")
		)
		(fp_line
			(start -0.107 -0.201)
			(end -0.107 0.198)
			(stroke
				(width 0.1)
				(type solid)
			)
			(layer "F.SilkS")
		)
		(fp_line
			(start -0.107 -0.201)
			(end 0.092 -0.001)
			(stroke
				(width 0.1)
				(type solid)
			)
			(layer "F.SilkS")
		)
		(fp_line
			(start 0.092 -0.201)
			(end 0.092 0.198)
			(stroke
				(width 0.1)
				(type solid)
			)
			(layer "F.SilkS")
		)
		(fp_line
			(start -0.271 -0.349)
			(end 0.269 -0.349)
			(stroke
				(width 0.15)
				(type solid)
			)
			(layer "F.SilkS")
		)
		(fp_rect
			(start -1.2192 -0.6096)
			(end 1.27 0.6016)
			(stroke
				(width 0.05)
				(type solid)
			)
			(fill no)
			(layer "F.CrtYd")
		)
		(fp_line
			(start -0.202 0.201)
			(end 0.1 -0.001)
			(stroke
				(width 0.15)
				(type solid)
			)
			(layer "F.Fab")
		)
		(fp_line
			(start 0.198 0.201)
			(end 0.198 -0.101)
			(stroke
				(width 0.15)
				(type solid)
			)
			(layer "F.Fab")
		)
		(fp_line
			(start -0.849 0.025)
			(end -0.442 0.381)
			(stroke
				(width 0.15)
				(type solid)
			)
			(layer "F.Fab")
		)
		(fp_line
			(start -0.6 -0.001)
			(end -0.202 -0.001)
			(stroke
				(width 0.15)
				(type solid)
			)
			(layer "F.Fab")
		)
		(fp_line
			(start -0.202 -0.001)
			(end -0.202 0.201)
			(stroke
				(width 0.15)
				(type solid)
			)
			(layer "F.Fab")
		)
		(fp_line
			(start 0.1 -0.001)
			(end -0.202 -0.201)
			(stroke
				(width 0.15)
				(type solid)
			)
			(layer "F.Fab")
		)
		(fp_line
			(start 0.198 -0.001)
			(end 0.596 -0.001)
			(stroke
				(width 0.15)
				(type solid)
			)
			(layer "F.Fab")
		)
		(fp_line
			(start -0.202 -0.201)
			(end -0.202 -0.001)
			(stroke
				(width 0.15)
				(type solid)
			)
			(layer "F.Fab")
		)
		(fp_line
			(start 0.198 -0.201)
			(end 0.198 -0.101)
			(stroke
				(width 0.15)
				(type solid)
			)
			(layer "F.Fab")
		)
		(fp_rect
			(start -0.849 -0.401)
			(end 0.849 0.401)
			(stroke
				(width 0.15)
				(type solid)
			)
			(fill no)
			(layer "F.Fab")
		)
		(pad "1" smd rect
			(at -0.751 -0.001 90)
			(size 0.8 0.8)
			(layers "F.Cu" "F.Mask" "F.Paste")
			(net 318 "Net-(D13-Pad1)")
			(pinfunction "1")
			(pintype "passive")
		)
		(pad "2" smd rect
			(at 0.749 -0.001 90)
			(size 0.8 0.8)
			(layers "F.Cu" "F.Mask" "F.Paste")
			(net 1 "GND")
			(pinfunction "2")
			(pintype "passive")
		)
	)
	(footprint "antmicro-footprints:LED_0603_1608Metric_G"
		(layer "F.Cu")
		(at 91.750501 116.426 -90)
		(descr "LED SMD 0603 Green")
		(tags "LED SMD 0603 Green")
		(property "Reference" "D7"
			(at -0.001 -0.901 270)
			(layer "F.SilkS")
			(hide yes)
			(effects
				(font
					(size 0.7 0.7)
					(thickness 0.15)
				)
				(justify left bottom)
			)
		)
		(property "Value" "LED_G_0603_KP-1608CGCK"
			(at -0.001 1.599 270)
			(layer "F.Fab")
			(effects
				(font
					(size 0.7 0.7)
					(thickness 0.15)
				)
				(justify left bottom)
			)
		)
		(property "Datasheet" "http://www.farnell.com/datasheets/2045956.pdf"
			(at 0 0 270)
			(layer "F.Fab")
			(hide yes)
			(effects
				(font
					(size 1.27 1.27)
					(thickness 0.15)
				)
			)
		)
		(property "Author" "Antmicro"
			(at -24.675499 208.176501 0)
			(layer "F.Fab")
			(hide yes)
			(effects
				(font
					(size 1 1)
					(thickness 0.15)
				)
			)
		)
		(property "License" "Apache-2.0"
			(at -24.675499 208.176501 0)
			(layer "F.Fab")
			(hide yes)
			(effects
				(font
					(size 1 1)
					(thickness 0.15)
				)
			)
		)
		(property "MPN" "KP-1608CGCK"
			(at -24.675499 208.176501 0)
			(layer "F.Fab")
			(hide yes)
			(effects
				(font
					(size 1 1)
					(thickness 0.15)
				)
			)
		)
		(property "Manufacturer" "Kingbright"
			(at -24.675499 208.176501 0)
			(layer "F.Fab")
			(hide yes)
			(effects
				(font
					(size 1 1)
					(thickness 0.15)
				)
			)
		)
		(sheetname "/FPGA bank 14/")
		(sheetfile "fpga-bank-14.kicad_sch")
		(attr smd)
		(fp_line
			(start -0.271 0.348)
			(end 0.269 0.348)
			(stroke
				(width 0.15)
				(type solid)
			)
			(layer "F.SilkS")
		)
		(fp_line
			(start 1.249 0.319)
			(end 1.249 -0.321)
			(stroke
				(width 0.15)
				(type solid)
			)
			(layer "F.SilkS")
		)
		(fp_line
			(start -0.107 -0.001)
			(end -0.291 -0.001)
			(stroke
				(width 0.1)
				(type solid)
			)
			(layer "F.SilkS")
		)
		(fp_line
			(start 0.092 -0.001)
			(end -0.107 0.198)
			(stroke
				(width 0.1)
				(type solid)
			)
			(layer "F.SilkS")
		)
		(fp_line
			(start 0.092 -0.001)
			(end 0.292 -0.001)
			(stroke
				(width 0.1)
				(type solid)
			)
			(layer "F.SilkS")
		)
		(fp_line
			(start -0.107 -0.201)
			(end -0.107 0.198)
			(stroke
				(width 0.1)
				(type solid)
			)
			(layer "F.SilkS")
		)
		(fp_line
			(start -0.107 -0.201)
			(end 0.092 -0.001)
			(stroke
				(width 0.1)
				(type solid)
			)
			(layer "F.SilkS")
		)
		(fp_line
			(start 0.092 -0.201)
			(end 0.092 0.198)
			(stroke
				(width 0.1)
				(type solid)
			)
			(layer "F.SilkS")
		)
		(fp_line
			(start -0.271 -0.349)
			(end 0.269 -0.349)
			(stroke
				(width 0.15)
				(type solid)
			)
			(layer "F.SilkS")
		)
		(fp_rect
			(start -1.2192 -0.6096)
			(end 1.27 0.6016)
			(stroke
				(width 0.05)
				(type solid)
			)
			(fill no)
			(layer "F.CrtYd")
		)
		(fp_line
			(start -0.202 0.201)
			(end 0.1 -0.001)
			(stroke
				(width 0.15)
				(type solid)
			)
			(layer "F.Fab")
		)
		(fp_line
			(start 0.198 0.201)
			(end 0.198 -0.101)
			(stroke
				(width 0.15)
				(type solid)
			)
			(layer "F.Fab")
		)
		(fp_line
			(start -0.849 0.025)
			(end -0.442 0.381)
			(stroke
				(width 0.15)
				(type solid)
			)
			(layer "F.Fab")
		)
		(fp_line
			(start -0.6 -0.001)
			(end -0.202 -0.001)
			(stroke
				(width 0.15)
				(type solid)
			)
			(layer "F.Fab")
		)
		(fp_line
			(start -0.202 -0.001)
			(end -0.202 0.201)
			(stroke
				(width 0.15)
				(type solid)
			)
			(layer "F.Fab")
		)
		(fp_line
			(start 0.1 -0.001)
			(end -0.202 -0.201)
			(stroke
				(width 0.15)
				(type solid)
			)
			(layer "F.Fab")
		)
		(fp_line
			(start 0.198 -0.001)
			(end 0.596 -0.001)
			(stroke
				(width 0.15)
				(type solid)
			)
			(layer "F.Fab")
		)
		(fp_line
			(start -0.202 -0.201)
			(end -0.202 -0.001)
			(stroke
				(width 0.15)
				(type solid)
			)
			(layer "F.Fab")
		)
		(fp_line
			(start 0.198 -0.201)
			(end 0.198 -0.101)
			(stroke
				(width 0.15)
				(type solid)
			)
			(layer "F.Fab")
		)
		(fp_rect
			(start -0.849 -0.401)
			(end 0.849 0.401)
			(stroke
				(width 0.15)
				(type solid)
			)
			(fill no)
			(layer "F.Fab")
		)
		(pad "1" smd rect
			(at -0.751 -0.001 90)
			(size 0.8 0.8)
			(layers "F.Cu" "F.Mask" "F.Paste")
			(net 200 "+3V3")
			(pinfunction "1")
			(pintype "passive")
		)
		(pad "2" smd rect
			(at 0.749 -0.001 90)
			(size 0.8 0.8)
			(layers "F.Cu" "F.Mask" "F.Paste")
			(net 310 "Net-(D7-Pad2)")
			(pinfunction "2")
			(pintype "passive")
		)
	)
	(footprint "antmicro-footprints:C_0603_1608Metric"
		(layer "F.Cu")
		(at 192.745501 182.923 90)
		(descr "Capacitor SMD 0603")
		(tags "capacitor 0603")
		(property "Reference" "C183"
			(at -1.42757 -1.000252 90)
			(layer "F.SilkS")
			(hide yes)
			(effects
				(font
					(size 0.7 0.7)
					(thickness 0.15)
				)
				(justify left bottom)
			)
		)
		(property "Value" "C_22u_0603"
			(at -1.42757 1.770288 90)
			(layer "F.Fab")
			(effects
				(font
					(size 0.7 0.7)
					(thickness 0.15)
				)
				(justify left bottom)
			)
		)
		(property "Datasheet" "https://www.murata.com/products/productdetail?partno=GRM188R60J226MEA0%23"
			(at 0 0 90)
			(layer "F.Fab")
			(hide yes)
			(effects
				(font
					(size 1.27 1.27)
					(thickness 0.15)
				)
			)
		)
		(property "Author" "Antmicro"
			(at 375.668501 -9.822501 0)
			(layer "F.Fab")
			(hide yes)
			(effects
				(font
					(size 1 1)
					(thickness 0.15)
				)
			)
		)
		(property "Dielectric" ""
			(at 375.668501 -9.822501 0)
			(layer "F.Fab")
			(hide yes)
			(effects
				(font
					(size 1 1)
					(thickness 0.15)
				)
			)
		)
		(property "License" "Apache-2.0"
			(at 375.668501 -9.822501 0)
			(layer "F.Fab")
			(hide yes)
			(effects
				(font
					(size 1 1)
					(thickness 0.15)
				)
			)
		)
		(property "MPN" "GRM188R60J226MEA0D"
			(at 375.668501 -9.822501 0)
			(layer "F.Fab")
			(hide yes)
			(effects
				(font
					(size 1 1)
					(thickness 0.15)
				)
			)
		)
		(property "Manufacturer" "Murata"
			(at 375.668501 -9.822501 0)
			(layer "F.Fab")
			(hide yes)
			(effects
				(font
					(size 1 1)
					(thickness 0.15)
				)
			)
		)
		(property "Val" "22u"
			(at 375.668501 -9.822501 0)
			(layer "F.Fab")
			(hide yes)
			(effects
				(font
					(size 1 1)
					(thickness 0.15)
				)
			)
		)
		(property "Voltage" ""
			(at 375.668501 -9.822501 0)
			(layer "F.Fab")
			(hide yes)
			(effects
				(font
					(size 1 1)
					(thickness 0.15)
				)
			)
		)
		(sheetname "/Supply/")
		(sheetfile "supply.kicad_sch")
		(attr smd)
		(fp_line
			(start -0.3 -0.3)
			(end 0.3 -0.3)
			(stroke
				(width 0.15)
				(type solid)
			)
			(layer "F.SilkS")
		)
		(fp_line
			(start -0.3 0.3)
			(end 0.3 0.3)
			(stroke
				(width 0.15)
				(type solid)
			)
			(layer "F.SilkS")
		)
		(fp_rect
			(start -1.24 -0.7)
			(end 1.24 0.7)
			(stroke
				(width 0.05)
				(type solid)
			)
			(fill no)
			(layer "F.CrtYd")
		)
		(fp_rect
			(start -0.8 -0.4)
			(end 0.8 0.4)
			(stroke
				(width 0.15)
				(type solid)
			)
			(fill no)
			(layer "F.Fab")
		)
		(pad "1" smd roundrect
			(at -0.7 0 90)
			(size 0.6 0.8)
			(layers "F.Cu" "F.Mask" "F.Paste")
			(roundrect_rratio 0.2)
			(net 1 "GND")
			(pintype "passive")
		)
		(pad "2" smd roundrect
			(at 0.7 0 90)
			(size 0.6 0.8)
			(layers "F.Cu" "F.Mask" "F.Paste")
			(roundrect_rratio 0.2)
			(net 51 "/Supply/1V8_local")
			(pintype "passive")
		)
	)
	(footprint "antmicro-footprints:C_0402_1005Metric"
		(layer "F.Cu")
		(at 93 190 90)
		(descr "Capacitor SMD 0402")
		(tags "capacitor SMD 0402")
		(property "Reference" "C128"
			(at 0 -0.699 90)
			(layer "F.SilkS")
			(hide yes)
			(effects
				(font
					(size 0.7 0.7)
					(thickness 0.15)
				)
				(justify left bottom)
			)
		)
		(property "Value" "C_100n_0402"
			(at -1.022927 2.155213 90)
			(layer "F.Fab")
			(effects
				(font
					(size 0.7 0.7)
					(thickness 0.15)
				)
				(justify left bottom)
			)
		)
		(property "Datasheet" "https://www.murata.com/products/productdetail?partno=GRM155R61H104KE14%23"
			(at 0 0 90)
			(layer "F.Fab")
			(hide yes)
			(effects
				(font
					(size 1.27 1.27)
					(thickness 0.15)
				)
			)
		)
		(property "Author" "Antmicro"
			(at 283 97 0)
			(layer "F.Fab")
			(hide yes)
			(effects
				(font
					(size 1 1)
					(thickness 0.15)
				)
			)
		)
		(property "Dielectric" "X5R"
			(at 283 97 0)
			(layer "F.Fab")
			(hide yes)
			(effects
				(font
					(size 1 1)
					(thickness 0.15)
				)
			)
		)
		(property "License" "Apache-2.0"
			(at 283 97 0)
			(layer "F.Fab")
			(hide yes)
			(effects
				(font
					(size 1 1)
					(thickness 0.15)
				)
			)
		)
		(property "MPN" "GRM155R61H104KE14D"
			(at 283 97 0)
			(layer "F.Fab")
			(hide yes)
			(effects
				(font
					(size 1 1)
					(thickness 0.15)
				)
			)
		)
		(property "Manufacturer" "Murata"
			(at 283 97 0)
			(layer "F.Fab")
			(hide yes)
			(effects
				(font
					(size 1 1)
					(thickness 0.15)
				)
			)
		)
		(property "Val" "100n"
			(at 283 97 0)
			(layer "F.Fab")
			(hide yes)
			(effects
				(font
					(size 1 1)
					(thickness 0.15)
				)
			)
		)
		(property "Voltage" "50V"
			(at 283 97 0)
			(layer "F.Fab")
			(hide yes)
			(effects
				(font
					(size 1 1)
					(thickness 0.15)
				)
			)
		)
		(sheetname "/Debug FTDI/")
		(sheetfile "debug-ftdi.kicad_sch")
		(attr smd)
		(fp_rect
			(start -0.9659 -0.481258)
			(end 0.9649 0.458742)
			(stroke
				(width 0.05)
				(type solid)
			)
			(fill no)
			(layer "F.CrtYd")
		)
		(fp_line
			(start 0.499 -0.25)
			(end 0.499 0.248)
			(stroke
				(width 0.15)
				(type solid)
			)
			(layer "F.Fab")
		)
		(fp_line
			(start -0.499 -0.25)
			(end 0.499 -0.25)
			(stroke
				(width 0.15)
				(type solid)
			)
			(layer "F.Fab")
		)
		(fp_line
			(start 0.499 0.248)
			(end -0.499 0.248)
			(stroke
				(width 0.15)
				(type solid)
			)
			(layer "F.Fab")
		)
		(fp_line
			(start -0.499 0.248)
			(end -0.499 -0.25)
			(stroke
				(width 0.15)
				(type solid)
			)
			(layer "F.Fab")
		)
		(pad "1" smd roundrect
			(at -0.484 0 90)
			(size 0.59 0.64)
			(layers "F.Cu" "F.Mask" "F.Paste")
			(roundrect_rratio 0.25)
			(net 1 "GND")
			(pintype "passive")
		)
		(pad "2" smd roundrect
			(at 0.484 0 90)
			(size 0.59 0.64)
			(layers "F.Cu" "F.Mask" "F.Paste")
			(roundrect_rratio 0.25)
			(net 6 "/Debug FTDI/FTDI_3V3")
			(pintype "passive")
		)
	)
)
